(kicad_pcb
	(version 20260206)
	(generator "pcbnew")
	(generator_version "10.0")
	(general
		(thickness 1.6)
		(legacy_teardrops no)
	)
	(paper "A4")
	(title_block
		(title "01162023_DA0F0TEBIF0_F0T_Expander_BD_F_brd_V02_OCP.brd")
		(comment 1 "Grand Teton / footprints 6721-6726 of 9728")
	)
	(layers
		(0 "F.Cu" signal "TOP")
		(4 "In1.Cu" signal "GND")
		(6 "In2.Cu" signal "VCC")
		(8 "In3.Cu" signal "VCC1")
		(10 "In4.Cu" signal "GND1")
		(12 "In5.Cu" signal "IN1")
		(14 "In6.Cu" signal "GND2")
		(16 "In7.Cu" signal "IN2")
		(18 "In8.Cu" signal "GND3")
		(20 "In9.Cu" signal "IN3")
		(22 "In10.Cu" signal "GND4")
		(24 "In11.Cu" signal "IN4")
		(26 "In12.Cu" signal "GND5")
		(28 "In13.Cu" signal "IN5")
		(30 "In14.Cu" signal "GND6")
		(32 "In15.Cu" signal "IN6")
		(34 "In16.Cu" signal "GND7")
		(2 "B.Cu" signal "BOTTOM")
		(9 "F.Adhes" user "F.Adhesive")
		(11 "B.Adhes" user "B.Adhesive")
		(13 "F.Paste" user "Package Geometry/Pastemask Top")
		(15 "B.Paste" user "Package Geometry/Pastemask Bottom")
		(5 "F.SilkS" user "Ref Des/Silkscreen Top")
		(7 "B.SilkS" user "Ref Des/Silkscreen Bottom")
		(1 "F.Mask" user "Board Geometry/Soldermask Top")
		(3 "B.Mask" user "Board Geometry/Soldermask Bottom")
		(17 "Dwgs.User" user "User.Drawings")
		(19 "Cmts.User" user "User.Comments")
		(21 "Eco1.User" user "User.Eco1")
		(23 "Eco2.User" user "User.Eco2")
		(25 "Edge.Cuts" user "Board Geometry/Outline")
		(27 "Margin" user)
		(31 "F.CrtYd" user "Package Geometry/Place Bound Top")
		(29 "B.CrtYd" user "Package Geometry/Place Bound Bottom")
		(35 "F.Fab" user "Ref Des/Assembly Top")
		(33 "B.Fab" user "Ref Des/Assembly Bottom")
	)
	(footprint ""
		(layer "F.Cu")
		(at 2.87528 -63.086234 180)
		(property "Reference" "PR6907"
			(at 0 0 180)
			(layer "F.SilkS")
			(hide yes)
			(effects
				(font
					(size 1.27 1.27)
				)
			)
		)
		(property "Value" ""
			(at 0 0 180)
			(layer "F.Fab")
			(effects
				(font
					(size 1.27 1.27)
				)
			)
		)
		(duplicate_pad_numbers_are_jumpers no)
		(fp_line
			(start 0.7874 0.4064)
			(end -0.7874 0.4064)
			(stroke
				(width 0.1524)
				(type default)
			)
			(layer "F.SilkS")
		)
		(fp_line
			(start 0.7874 -0.4064)
			(end 0.7874 0.4064)
			(stroke
				(width 0.1524)
				(type default)
			)
			(layer "F.SilkS")
		)
		(fp_line
			(start -0.7874 0.4064)
			(end -0.7874 -0.4064)
			(stroke
				(width 0.1524)
				(type default)
			)
			(layer "F.SilkS")
		)
		(fp_line
			(start -0.7874 -0.4064)
			(end 0.7874 -0.4064)
			(stroke
				(width 0.1524)
				(type default)
			)
			(layer "F.SilkS")
		)
		(fp_line
			(start 0.67945 0.3048)
			(end 0.120396 0.3048)
			(stroke
				(width 0.1)
				(type default)
			)
			(layer "F.Fab")
		)
		(fp_line
			(start 0.67945 -0.3048)
			(end 0.67945 0.3048)
			(stroke
				(width 0.1)
				(type default)
			)
			(layer "F.Fab")
		)
		(fp_line
			(start 0.12065 -0.2794)
			(end 0.12065 -0.3048)
			(stroke
				(width 0.1)
				(type default)
			)
			(layer "F.Fab")
		)
		(fp_line
			(start 0.12065 -0.3048)
			(end 0.67945 -0.3048)
			(stroke
				(width 0.1)
				(type default)
			)
			(layer "F.Fab")
		)
		(fp_line
			(start 0.120396 0.3048)
			(end 0.120396 0.2794)
			(stroke
				(width 0.1)
				(type default)
			)
			(layer "F.Fab")
		)
		(fp_line
			(start 0.120396 0.2794)
			(end -0.12065 0.2794)
			(stroke
				(width 0.1)
				(type default)
			)
			(layer "F.Fab")
		)
		(fp_line
			(start -0.12065 0.3048)
			(end -0.67945 0.3048)
			(stroke
				(width 0.1)
				(type default)
			)
			(layer "F.Fab")
		)
		(fp_line
			(start -0.12065 0.2794)
			(end -0.12065 0.3048)
			(stroke
				(width 0.1)
				(type default)
			)
			(layer "F.Fab")
		)
		(fp_line
			(start -0.12065 -0.2794)
			(end 0.12065 -0.2794)
			(stroke
				(width 0.1)
				(type default)
			)
			(layer "F.Fab")
		)
		(fp_line
			(start -0.12065 -0.305054)
			(end -0.12065 -0.2794)
			(stroke
				(width 0.1)
				(type default)
			)
			(layer "F.Fab")
		)
		(fp_line
			(start -0.67945 0.3048)
			(end -0.67945 -0.305054)
			(stroke
				(width 0.1)
				(type default)
			)
			(layer "F.Fab")
		)
		(fp_line
			(start -0.67945 -0.305054)
			(end -0.12065 -0.305054)
			(stroke
				(width 0.1)
				(type default)
			)
			(layer "F.Fab")
		)
		(pad "1" smd circle
			(at -0.40005 0 180)
			(size 0 0)
			(layers "F.Cu" "F.Mask" "F.Paste")
			(net "P12V_SSD0_PG_G1")
		)
		(pad "2" smd circle
			(at 0.40005 0 180)
			(size 0 0)
			(layers "F.Cu" "F.Mask" "F.Paste")
			(net "GND")
		)
	)
	(footprint ""
		(layer "F.Cu")
		(at 206.623158 -80.611472)
		(property "Reference" "R4306"
			(at 0 0 0)
			(layer "F.SilkS")
			(hide yes)
			(effects
				(font
					(size 1.27 1.27)
				)
			)
		)
		(property "Value" ""
			(at 0 0 0)
			(layer "F.Fab")
			(effects
				(font
					(size 1.27 1.27)
				)
			)
		)
		(duplicate_pad_numbers_are_jumpers no)
		(fp_line
			(start -0.7874 -0.4064)
			(end 0.7874 -0.4064)
			(stroke
				(width 0.1524)
				(type default)
			)
			(layer "F.SilkS")
		)
		(fp_line
			(start -0.7874 0.4064)
			(end -0.7874 -0.4064)
			(stroke
				(width 0.1524)
				(type default)
			)
			(layer "F.SilkS")
		)
		(fp_line
			(start 0.7874 -0.4064)
			(end 0.7874 0.4064)
			(stroke
				(width 0.1524)
				(type default)
			)
			(layer "F.SilkS")
		)
		(fp_line
			(start 0.7874 0.4064)
			(end -0.7874 0.4064)
			(stroke
				(width 0.1524)
				(type default)
			)
			(layer "F.SilkS")
		)
		(fp_line
			(start -0.67945 -0.305054)
			(end -0.12065 -0.305054)
			(stroke
				(width 0.1)
				(type default)
			)
			(layer "F.Fab")
		)
		(fp_line
			(start -0.67945 0.3048)
			(end -0.67945 -0.305054)
			(stroke
				(width 0.1)
				(type default)
			)
			(layer "F.Fab")
		)
		(fp_line
			(start -0.12065 -0.305054)
			(end -0.12065 -0.2794)
			(stroke
				(width 0.1)
				(type default)
			)
			(layer "F.Fab")
		)
		(fp_line
			(start -0.12065 -0.2794)
			(end 0.12065 -0.2794)
			(stroke
				(width 0.1)
				(type default)
			)
			(layer "F.Fab")
		)
		(fp_line
			(start -0.12065 0.2794)
			(end -0.12065 0.3048)
			(stroke
				(width 0.1)
				(type default)
			)
			(layer "F.Fab")
		)
		(fp_line
			(start -0.12065 0.3048)
			(end -0.67945 0.3048)
			(stroke
				(width 0.1)
				(type default)
			)
			(layer "F.Fab")
		)
		(fp_line
			(start 0.120396 0.2794)
			(end -0.12065 0.2794)
			(stroke
				(width 0.1)
				(type default)
			)
			(layer "F.Fab")
		)
		(fp_line
			(start 0.120396 0.3048)
			(end 0.120396 0.2794)
			(stroke
				(width 0.1)
				(type default)
			)
			(layer "F.Fab")
		)
		(fp_line
			(start 0.12065 -0.3048)
			(end 0.67945 -0.3048)
			(stroke
				(width 0.1)
				(type default)
			)
			(layer "F.Fab")
		)
		(fp_line
			(start 0.12065 -0.2794)
			(end 0.12065 -0.3048)
			(stroke
				(width 0.1)
				(type default)
			)
			(layer "F.Fab")
		)
		(fp_line
			(start 0.67945 -0.3048)
			(end 0.67945 0.3048)
			(stroke
				(width 0.1)
				(type default)
			)
			(layer "F.Fab")
		)
		(fp_line
			(start 0.67945 0.3048)
			(end 0.120396 0.3048)
			(stroke
				(width 0.1)
				(type default)
			)
			(layer "F.Fab")
		)
		(pad "1" smd circle
			(at -0.40005 0)
			(size 0 0)
			(layers "F.Cu" "F.Mask" "F.Paste")
			(net "SSD4_LED_R")
		)
		(pad "2" smd circle
			(at 0.40005 0)
			(size 0 0)
			(layers "F.Cu" "F.Mask" "F.Paste")
			(net "SSD4_LED")
		)
	)
	(footprint ""
		(layer "F.Cu")
		(at 115.356386 -86.469982 180)
		(property "Reference" "R1146"
			(at 0 0 180)
			(layer "F.SilkS")
			(hide yes)
			(effects
				(font
					(size 1.27 1.27)
				)
			)
		)
		(property "Value" ""
			(at 0 0 180)
			(layer "F.Fab")
			(effects
				(font
					(size 1.27 1.27)
				)
			)
		)
		(duplicate_pad_numbers_are_jumpers no)
		(fp_line
			(start -0.7874 -0.4064)
			(end 0.7874 -0.4064)
			(stroke
				(width 0.1524)
				(type default)
			)
			(layer "F.SilkS")
		)
		(fp_line
			(start 0.67945 0.3048)
			(end 0.120396 0.3048)
			(stroke
				(width 0.1)
				(type default)
			)
			(layer "F.Fab")
		)
		(fp_line
			(start 0.67945 -0.3048)
			(end 0.67945 0.3048)
			(stroke
				(width 0.1)
				(type default)
			)
			(layer "F.Fab")
		)
		(fp_line
			(start 0.12065 -0.2794)
			(end 0.12065 -0.3048)
			(stroke
				(width 0.1)
				(type default)
			)
			(layer "F.Fab")
		)
		(fp_line
			(start 0.12065 -0.3048)
			(end 0.67945 -0.3048)
			(stroke
				(width 0.1)
				(type default)
			)
			(layer "F.Fab")
		)
		(fp_line
			(start 0.120396 0.3048)
			(end 0.120396 0.2794)
			(stroke
				(width 0.1)
				(type default)
			)
			(layer "F.Fab")
		)
		(fp_line
			(start 0.120396 0.2794)
			(end -0.12065 0.2794)
			(stroke
				(width 0.1)
				(type default)
			)
			(layer "F.Fab")
		)
		(fp_line
			(start -0.12065 0.3048)
			(end -0.67945 0.3048)
			(stroke
				(width 0.1)
				(type default)
			)
			(layer "F.Fab")
		)
		(fp_line
			(start -0.12065 0.2794)
			(end -0.12065 0.3048)
			(stroke
				(width 0.1)
				(type default)
			)
			(layer "F.Fab")
		)
		(fp_line
			(start -0.12065 -0.2794)
			(end 0.12065 -0.2794)
			(stroke
				(width 0.1)
				(type default)
			)
			(layer "F.Fab")
		)
		(fp_line
			(start -0.12065 -0.305054)
			(end -0.12065 -0.2794)
			(stroke
				(width 0.1)
				(type default)
			)
			(layer "F.Fab")
		)
		(fp_line
			(start -0.67945 0.3048)
			(end -0.67945 -0.305054)
			(stroke
				(width 0.1)
				(type default)
			)
			(layer "F.Fab")
		)
		(fp_line
			(start -0.67945 -0.305054)
			(end -0.12065 -0.305054)
			(stroke
				(width 0.1)
				(type default)
			)
			(layer "F.Fab")
		)
		(pad "1" smd circle
			(at -0.40005 0 180)
			(size 0 0)
			(layers "F.Cu" "F.Mask" "F.Paste")
			(net "CLK_100M_DB800ZL_SSD5_R_DP")
		)
		(pad "2" smd circle
			(at 0.40005 0 180)
			(size 0 0)
			(layers "F.Cu" "F.Mask" "F.Paste")
			(net "CLK_100M_DB800ZL_SSD5_DP")
		)
	)
	(footprint ""
		(layer "F.Cu")
		(at 320.354452 -223.389698 180)
		(property "Reference" "D15"
			(at 3.743452 0.103632 0)
			(unlocked yes)
			(layer "F.SilkS")
			(effects
				(font
					(size 0.7874 0.5842)
					(thickness 0.1524)
				)
				(justify left)
			)
		)
		(property "Value" ""
			(at 0 0 180)
			(layer "F.Fab")
			(effects
				(font
					(size 1.27 1.27)
				)
			)
		)
		(duplicate_pad_numbers_are_jumpers no)
		(fp_line
			(start 1.16078 0.4826)
			(end -0.64008 0.4826)
			(stroke
				(width 0.1524)
				(type default)
			)
			(layer "F.SilkS")
		)
		(fp_line
			(start 1.16078 -0.4826)
			(end 1.16078 0.4826)
			(stroke
				(width 0.1524)
				(type default)
			)
			(layer "F.SilkS")
		)
		(fp_line
			(start 1.03378 0.4826)
			(end -0.79248 0.4826)
			(stroke
				(width 0.1524)
				(type default)
			)
			(layer "F.SilkS")
		)
		(fp_line
			(start 1.03378 -0.4826)
			(end 1.03378 0.4826)
			(stroke
				(width 0.1524)
				(type default)
			)
			(layer "F.SilkS")
		)
		(fp_line
			(start 0.90678 0.4826)
			(end -0.90678 0.4826)
			(stroke
				(width 0.1524)
				(type default)
			)
			(layer "F.SilkS")
		)
		(fp_line
			(start 0.90678 -0.4826)
			(end 0.90678 0.4826)
			(stroke
				(width 0.1524)
				(type default)
			)
			(layer "F.SilkS")
		)
		(fp_line
			(start -0.64008 -0.4826)
			(end 1.16078 -0.4826)
			(stroke
				(width 0.1524)
				(type default)
			)
			(layer "F.SilkS")
		)
		(fp_line
			(start -0.79248 -0.4826)
			(end 1.03378 -0.4826)
			(stroke
				(width 0.1524)
				(type default)
			)
			(layer "F.SilkS")
		)
		(fp_line
			(start -0.89408 -0.4826)
			(end 0.90678 -0.4826)
			(stroke
				(width 0.1524)
				(type default)
			)
			(layer "F.SilkS")
		)
		(fp_line
			(start -0.90678 0.4826)
			(end -0.90678 -0.4699)
			(stroke
				(width 0.1524)
				(type default)
			)
			(layer "F.SilkS")
		)
		(fp_line
			(start 0.499872 0.249936)
			(end -0.499872 0.249936)
			(stroke
				(width 0.1)
				(type default)
			)
			(layer "F.Fab")
		)
		(fp_line
			(start 0.499872 -0.249936)
			(end 0.499872 0.249936)
			(stroke
				(width 0.1)
				(type default)
			)
			(layer "F.Fab")
		)
		(fp_line
			(start -0.499872 0.249936)
			(end -0.499872 -0.249936)
			(stroke
				(width 0.1)
				(type default)
			)
			(layer "F.Fab")
		)
		(fp_line
			(start -0.499872 -0.249936)
			(end 0.499872 -0.249936)
			(stroke
				(width 0.1)
				(type default)
			)
			(layer "F.Fab")
		)
		(pad "A" smd rect
			(at -0.47498 0 180)
			(size 0.6096 0.7112)
			(layers "F.Cu" "F.Mask" "F.Paste")
			(net "LED_POSTCODE_R_2")
		)
		(pad "C" smd rect
			(at 0.47498 0 180)
			(size 0.6096 0.7112)
			(layers "F.Cu" "F.Mask" "F.Paste")
			(net "FPGA_DEBUG_LED_R_N")
		)
	)
	(footprint ""
		(layer "F.Cu")
		(at 210.439 -203.835)
		(property "Reference" "C2556"
			(at 0 0 0)
			(layer "F.SilkS")
			(hide yes)
			(effects
				(font
					(size 1.27 1.27)
				)
			)
		)
		(property "Value" ""
			(at 0 0 0)
			(layer "F.Fab")
			(effects
				(font
					(size 1.27 1.27)
				)
			)
		)
		(duplicate_pad_numbers_are_jumpers no)
		(fp_line
			(start -0.7874 -0.4064)
			(end 0.7874 -0.4064)
			(stroke
				(width 0.1524)
				(type default)
			)
			(layer "F.SilkS")
		)
		(fp_line
			(start -0.7874 0.4064)
			(end -0.7874 -0.4064)
			(stroke
				(width 0.1524)
				(type default)
			)
			(layer "F.SilkS")
		)
		(fp_line
			(start 0.7874 -0.4064)
			(end 0.7874 0.4064)
			(stroke
				(width 0.1524)
				(type default)
			)
			(layer "F.SilkS")
		)
		(fp_line
			(start 0.7874 0.4064)
			(end -0.7874 0.4064)
			(stroke
				(width 0.1524)
				(type default)
			)
			(layer "F.SilkS")
		)
		(fp_line
			(start -0.67945 -0.305054)
			(end -0.12065 -0.305054)
			(stroke
				(width 0.1)
				(type default)
			)
			(layer "F.Fab")
		)
		(fp_line
			(start -0.67945 0.3048)
			(end -0.67945 -0.305054)
			(stroke
				(width 0.1)
				(type default)
			)
			(layer "F.Fab")
		)
		(fp_line
			(start -0.12065 -0.305054)
			(end -0.12065 -0.2794)
			(stroke
				(width 0.1)
				(type default)
			)
			(layer "F.Fab")
		)
		(fp_line
			(start -0.12065 -0.2794)
			(end 0.12065 -0.2794)
			(stroke
				(width 0.1)
				(type default)
			)
			(layer "F.Fab")
		)
		(fp_line
			(start -0.12065 0.2794)
			(end -0.12065 0.3048)
			(stroke
				(width 0.1)
				(type default)
			)
			(layer "F.Fab")
		)
		(fp_line
			(start -0.12065 0.3048)
			(end -0.67945 0.3048)
			(stroke
				(width 0.1)
				(type default)
			)
			(layer "F.Fab")
		)
		(fp_line
			(start 0.120396 0.2794)
			(end -0.12065 0.2794)
			(stroke
				(width 0.1)
				(type default)
			)
			(layer "F.Fab")
		)
		(fp_line
			(start 0.120396 0.3048)
			(end 0.120396 0.2794)
			(stroke
				(width 0.1)
				(type default)
			)
			(layer "F.Fab")
		)
		(fp_line
			(start 0.12065 -0.3048)
			(end 0.67945 -0.3048)
			(stroke
				(width 0.1)
				(type default)
			)
			(layer "F.Fab")
		)
		(fp_line
			(start 0.12065 -0.2794)
			(end 0.12065 -0.3048)
			(stroke
				(width 0.1)
				(type default)
			)
			(layer "F.Fab")
		)
		(fp_line
			(start 0.67945 -0.3048)
			(end 0.67945 0.3048)
			(stroke
				(width 0.1)
				(type default)
			)
			(layer "F.Fab")
		)
		(fp_line
			(start 0.67945 0.3048)
			(end 0.120396 0.3048)
			(stroke
				(width 0.1)
				(type default)
			)
			(layer "F.Fab")
		)
		(pad "1" smd circle
			(at -0.40005 0)
			(size 0 0)
			(layers "F.Cu" "F.Mask" "F.Paste")
			(net "GND")
		)
		(pad "2" smd circle
			(at 0.40005 0)
			(size 0 0)
			(layers "F.Cu" "F.Mask" "F.Paste")
			(net "P1V2_AUX")
		)
	)
	(footprint ""
		(layer "F.Cu")
		(at 310.467756 -56.353456)
		(property "Reference" "C2873"
			(at 0 0 0)
			(layer "F.SilkS")
			(hide yes)
			(effects
				(font
					(size 1.27 1.27)
				)
			)
		)
		(property "Value" ""
			(at 0 0 0)
			(layer "F.Fab")
			(effects
				(font
					(size 1.27 1.27)
				)
			)
		)
		(duplicate_pad_numbers_are_jumpers no)
		(fp_line
			(start -0.7874 -0.4064)
			(end 0.7874 -0.4064)
			(stroke
				(width 0.1524)
				(type default)
			)
			(layer "F.SilkS")
		)
		(fp_line
			(start -0.7874 0.4064)
			(end -0.7874 -0.4064)
			(stroke
				(width 0.1524)
				(type default)
			)
			(layer "F.SilkS")
		)
		(fp_line
			(start 0.7874 -0.4064)
			(end 0.7874 0.4064)
			(stroke
				(width 0.1524)
				(type default)
			)
			(layer "F.SilkS")
		)
		(fp_line
			(start 0.7874 0.4064)
			(end -0.7874 0.4064)
			(stroke
				(width 0.1524)
				(type default)
			)
			(layer "F.SilkS")
		)
		(fp_line
			(start -0.67945 -0.305054)
			(end -0.12065 -0.305054)
			(stroke
				(width 0.1)
				(type default)
			)
			(layer "F.Fab")
		)
		(fp_line
			(start -0.67945 0.3048)
			(end -0.67945 -0.305054)
			(stroke
				(width 0.1)
				(type default)
			)
			(layer "F.Fab")
		)
		(fp_line
			(start -0.12065 -0.305054)
			(end -0.12065 -0.2794)
			(stroke
				(width 0.1)
				(type default)
			)
			(layer "F.Fab")
		)
		(fp_line
			(start -0.12065 -0.2794)
			(end 0.12065 -0.2794)
			(stroke
				(width 0.1)
				(type default)
			)
			(layer "F.Fab")
		)
		(fp_line
			(start -0.12065 0.2794)
			(end -0.12065 0.3048)
			(stroke
				(width 0.1)
				(type default)
			)
			(layer "F.Fab")
		)
		(fp_line
			(start -0.12065 0.3048)
			(end -0.67945 0.3048)
			(stroke
				(width 0.1)
				(type default)
			)
			(layer "F.Fab")
		)
		(fp_line
			(start 0.120396 0.2794)
			(end -0.12065 0.2794)
			(stroke
				(width 0.1)
				(type default)
			)
			(layer "F.Fab")
		)
		(fp_line
			(start 0.120396 0.3048)
			(end 0.120396 0.2794)
			(stroke
				(width 0.1)
				(type default)
			)
			(layer "F.Fab")
		)
		(fp_line
			(start 0.12065 -0.3048)
			(end 0.67945 -0.3048)
			(stroke
				(width 0.1)
				(type default)
			)
			(layer "F.Fab")
		)
		(fp_line
			(start 0.12065 -0.2794)
			(end 0.12065 -0.3048)
			(stroke
				(width 0.1)
				(type default)
			)
			(layer "F.Fab")
		)
		(fp_line
			(start 0.67945 -0.3048)
			(end 0.67945 0.3048)
			(stroke
				(width 0.1)
				(type default)
			)
			(layer "F.Fab")
		)
		(fp_line
			(start 0.67945 0.3048)
			(end 0.120396 0.3048)
			(stroke
				(width 0.1)
				(type default)
			)
			(layer "F.Fab")
		)
		(pad "1" smd circle
			(at -0.40005 0)
			(size 0 0)
			(layers "F.Cu" "F.Mask" "F.Paste")
			(net "SSD10_PWR_EN_R")
		)
		(pad "2" smd circle
			(at 0.40005 0)
			(size 0 0)
			(layers "F.Cu" "F.Mask" "F.Paste")
			(net "GND")
		)
	)
)
